(kicad_pcb
	(version 20260206)
	(generator "pcbnew")
	(generator_version "10.0")
	(general
		(thickness 1.6)
		(legacy_teardrops no)
	)
	(paper "A4")
	(title_block
		(title "04192023_DAF0TMB3IC0_F0TG_MB_C_brd_V02_OCP.brd")
		(comment 1 "Grand Teton / footprints 6960-6965 of 8354")
	)
	(layers
		(0 "F.Cu" signal "TOP")
		(4 "In1.Cu" signal "GND")
		(6 "In2.Cu" signal "IN1")
		(8 "In3.Cu" signal "GND1")
		(10 "In4.Cu" signal "IN2")
		(12 "In5.Cu" signal "GND2")
		(14 "In6.Cu" signal "IN3")
		(16 "In7.Cu" signal "GND3")
		(18 "In8.Cu" signal "VCC")
		(20 "In9.Cu" signal "VCC1")
		(22 "In10.Cu" signal "GND4")
		(24 "In11.Cu" signal "IN4")
		(26 "In12.Cu" signal "GND5")
		(28 "In13.Cu" signal "IN5")
		(30 "In14.Cu" signal "GND6")
		(32 "In15.Cu" signal "IN6")
		(34 "In16.Cu" signal "GND7")
		(2 "B.Cu" signal "BOTTOM")
		(9 "F.Adhes" user "F.Adhesive")
		(11 "B.Adhes" user "B.Adhesive")
		(13 "F.Paste" user "Package Geometry/Pastemask Top")
		(15 "B.Paste" user "Package Geometry/Pastemask Bottom")
		(5 "F.SilkS" user "Ref Des/Silkscreen Top")
		(7 "B.SilkS" user "Ref Des/Silkscreen Bottom")
		(1 "F.Mask" user "Board Geometry/Soldermask Top")
		(3 "B.Mask" user "Board Geometry/Soldermask Bottom")
		(17 "Dwgs.User" user "User.Drawings")
		(19 "Cmts.User" user "User.Comments")
		(21 "Eco1.User" user "User.Eco1")
		(23 "Eco2.User" user "User.Eco2")
		(25 "Edge.Cuts" user "Board Geometry/Outline")
		(27 "Margin" user)
		(31 "F.CrtYd" user "Package Geometry/Place Bound Top")
		(29 "B.CrtYd" user "Package Geometry/Place Bound Bottom")
		(35 "F.Fab" user "Ref Des/Assembly Top")
		(33 "B.Fab" user "Ref Des/Assembly Bottom")
	)
	(footprint ""
		(layer "B.Cu")
		(at 204.438758 -68.229734)
		(property "Reference" "R74"
			(at 0 0 0)
			(layer "B.SilkS")
			(hide yes)
			(effects
				(font
					(size 1.27 1.27)
				)
				(justify mirror)
			)
		)
		(property "Value" ""
			(at 0 0 0)
			(layer "B.Fab")
			(effects
				(font
					(size 1.27 1.27)
				)
				(justify mirror)
			)
		)
		(duplicate_pad_numbers_are_jumpers no)
		(fp_line
			(start -0.7874 -0.4064)
			(end -0.7874 0.4064)
			(stroke
				(width 0.1524)
				(type default)
			)
			(layer "B.SilkS")
		)
		(fp_line
			(start -0.7874 0.4064)
			(end 0.7874 0.4064)
			(stroke
				(width 0.1524)
				(type default)
			)
			(layer "B.SilkS")
		)
		(fp_line
			(start 0.7874 -0.4064)
			(end -0.7874 -0.4064)
			(stroke
				(width 0.1524)
				(type default)
			)
			(layer "B.SilkS")
		)
		(fp_line
			(start 0.7874 0.4064)
			(end 0.7874 -0.4064)
			(stroke
				(width 0.1524)
				(type default)
			)
			(layer "B.SilkS")
		)
		(fp_line
			(start -0.67945 -0.3048)
			(end -0.67945 0.3048)
			(stroke
				(width 0.1)
				(type default)
			)
			(layer "B.Fab")
		)
		(fp_line
			(start -0.67945 0.3048)
			(end -0.120396 0.3048)
			(stroke
				(width 0.1)
				(type default)
			)
			(layer "B.Fab")
		)
		(fp_line
			(start -0.12065 -0.3048)
			(end -0.67945 -0.3048)
			(stroke
				(width 0.1)
				(type default)
			)
			(layer "B.Fab")
		)
		(fp_line
			(start -0.12065 -0.2794)
			(end -0.12065 -0.3048)
			(stroke
				(width 0.1)
				(type default)
			)
			(layer "B.Fab")
		)
		(fp_line
			(start -0.120396 0.2794)
			(end 0.12065 0.2794)
			(stroke
				(width 0.1)
				(type default)
			)
			(layer "B.Fab")
		)
		(fp_line
			(start -0.120396 0.3048)
			(end -0.120396 0.2794)
			(stroke
				(width 0.1)
				(type default)
			)
			(layer "B.Fab")
		)
		(fp_line
			(start 0.12065 -0.305054)
			(end 0.12065 -0.2794)
			(stroke
				(width 0.1)
				(type default)
			)
			(layer "B.Fab")
		)
		(fp_line
			(start 0.12065 -0.2794)
			(end -0.12065 -0.2794)
			(stroke
				(width 0.1)
				(type default)
			)
			(layer "B.Fab")
		)
		(fp_line
			(start 0.12065 0.2794)
			(end 0.12065 0.3048)
			(stroke
				(width 0.1)
				(type default)
			)
			(layer "B.Fab")
		)
		(fp_line
			(start 0.12065 0.3048)
			(end 0.67945 0.3048)
			(stroke
				(width 0.1)
				(type default)
			)
			(layer "B.Fab")
		)
		(fp_line
			(start 0.67945 -0.305054)
			(end 0.12065 -0.305054)
			(stroke
				(width 0.1)
				(type default)
			)
			(layer "B.Fab")
		)
		(fp_line
			(start 0.67945 0.3048)
			(end 0.67945 -0.305054)
			(stroke
				(width 0.1)
				(type default)
			)
			(layer "B.Fab")
		)
		(pad "1" smd circle
			(at 0.40005 0 180)
			(size 0 0)
			(layers "B.Cu" "B.Mask" "B.Paste")
			(net "NCSI_BMC_TX_EN_R")
		)
		(pad "2" smd circle
			(at -0.40005 0 180)
			(size 0 0)
			(layers "B.Cu" "B.Mask" "B.Paste")
			(net "RMII_BMC_OCP_TX_EN")
		)
	)
	(footprint ""
		(layer "B.Cu")
		(at 108.46181 -393.242546 180)
		(property "Reference" "R900"
			(at 0 0 0)
			(layer "B.SilkS")
			(hide yes)
			(effects
				(font
					(size 1.27 1.27)
				)
				(justify mirror)
			)
		)
		(property "Value" ""
			(at 0 0 0)
			(layer "B.Fab")
			(effects
				(font
					(size 1.27 1.27)
				)
				(justify mirror)
			)
		)
		(duplicate_pad_numbers_are_jumpers no)
		(fp_line
			(start 1.2954 0.5842)
			(end 1.2954 -0.5842)
			(stroke
				(width 0.1524)
				(type default)
			)
			(layer "B.SilkS")
		)
		(fp_line
			(start 1.2954 -0.5842)
			(end -1.2954 -0.5842)
			(stroke
				(width 0.1524)
				(type default)
			)
			(layer "B.SilkS")
		)
		(fp_line
			(start -1.2954 0.5842)
			(end 1.2954 0.5842)
			(stroke
				(width 0.1524)
				(type default)
			)
			(layer "B.SilkS")
		)
		(fp_line
			(start -1.2954 -0.5842)
			(end -1.2954 0.5842)
			(stroke
				(width 0.1524)
				(type default)
			)
			(layer "B.SilkS")
		)
		(fp_line
			(start 1.1938 0.4064)
			(end 1.1938 -0.406654)
			(stroke
				(width 0.1)
				(type default)
			)
			(layer "B.Fab")
		)
		(fp_line
			(start 1.1938 -0.406654)
			(end 0.8636 -0.406654)
			(stroke
				(width 0.1)
				(type default)
			)
			(layer "B.Fab")
		)
		(fp_line
			(start 0.8636 0.4572)
			(end 0.8636 0.4318)
			(stroke
				(width 0.1)
				(type default)
			)
			(layer "B.Fab")
		)
		(fp_line
			(start 0.8636 0.4318)
			(end 0.8636 0.4064)
			(stroke
				(width 0.1)
				(type default)
			)
			(layer "B.Fab")
		)
		(fp_line
			(start 0.8636 0.4064)
			(end 1.1938 0.4064)
			(stroke
				(width 0.1)
				(type default)
			)
			(layer "B.Fab")
		)
		(fp_line
			(start 0.8636 -0.406654)
			(end 0.8636 -0.4572)
			(stroke
				(width 0.1)
				(type default)
			)
			(layer "B.Fab")
		)
		(fp_line
			(start 0.8636 -0.4572)
			(end -0.8636 -0.4572)
			(stroke
				(width 0.1)
				(type default)
			)
			(layer "B.Fab")
		)
		(fp_line
			(start -0.8636 0.4572)
			(end 0.8636 0.4572)
			(stroke
				(width 0.1)
				(type default)
			)
			(layer "B.Fab")
		)
		(fp_line
			(start -0.8636 0.4064)
			(end -0.8636 0.4572)
			(stroke
				(width 0.1)
				(type default)
			)
			(layer "B.Fab")
		)
		(fp_line
			(start -0.8636 -0.406654)
			(end -1.1938 -0.406654)
			(stroke
				(width 0.1)
				(type default)
			)
			(layer "B.Fab")
		)
		(fp_line
			(start -0.8636 -0.4572)
			(end -0.8636 -0.406654)
			(stroke
				(width 0.1)
				(type default)
			)
			(layer "B.Fab")
		)
		(fp_line
			(start -1.1938 0.4064)
			(end -0.8636 0.4064)
			(stroke
				(width 0.1)
				(type default)
			)
			(layer "B.Fab")
		)
		(fp_line
			(start -1.1938 -0.406654)
			(end -1.1938 0.4064)
			(stroke
				(width 0.1)
				(type default)
			)
			(layer "B.Fab")
		)
		(pad "1" smd rect
			(at 0.7366 0 90)
			(size 0.7112 0.8128)
			(layers "B.Cu" "B.Mask" "B.Paste")
			(net "P0V9_CPU1_RT3_2A_2D")
		)
		(pad "2" smd rect
			(at -0.7366 0 90)
			(size 0.7112 0.8128)
			(layers "B.Cu" "B.Mask" "B.Paste")
			(net "P0V9_CPU1_RT3_2A")
		)
	)
	(footprint ""
		(layer "B.Cu")
		(at 112.19434 -62.01791 -90)
		(property "Reference" "R6226"
			(at 0 0 90)
			(layer "B.SilkS")
			(hide yes)
			(effects
				(font
					(size 1.27 1.27)
				)
				(justify mirror)
			)
		)
		(property "Value" ""
			(at 0 0 90)
			(layer "B.Fab")
			(effects
				(font
					(size 1.27 1.27)
				)
				(justify mirror)
			)
		)
		(duplicate_pad_numbers_are_jumpers no)
		(fp_line
			(start -0.7874 0.4064)
			(end 0.7874 0.4064)
			(stroke
				(width 0.1524)
				(type default)
			)
			(layer "B.SilkS")
		)
		(fp_line
			(start 0.7874 0.4064)
			(end 0.7874 -0.4064)
			(stroke
				(width 0.1524)
				(type default)
			)
			(layer "B.SilkS")
		)
		(fp_line
			(start -0.7874 -0.4064)
			(end -0.7874 0.4064)
			(stroke
				(width 0.1524)
				(type default)
			)
			(layer "B.SilkS")
		)
		(fp_line
			(start 0.7874 -0.4064)
			(end -0.7874 -0.4064)
			(stroke
				(width 0.1524)
				(type default)
			)
			(layer "B.SilkS")
		)
		(fp_line
			(start -0.67945 0.3048)
			(end -0.120396 0.3048)
			(stroke
				(width 0.1)
				(type default)
			)
			(layer "B.Fab")
		)
		(fp_line
			(start -0.120396 0.3048)
			(end -0.120396 0.2794)
			(stroke
				(width 0.1)
				(type default)
			)
			(layer "B.Fab")
		)
		(fp_line
			(start 0.12065 0.3048)
			(end 0.67945 0.3048)
			(stroke
				(width 0.1)
				(type default)
			)
			(layer "B.Fab")
		)
		(fp_line
			(start 0.67945 0.3048)
			(end 0.67945 -0.305054)
			(stroke
				(width 0.1)
				(type default)
			)
			(layer "B.Fab")
		)
		(fp_line
			(start -0.120396 0.2794)
			(end 0.12065 0.2794)
			(stroke
				(width 0.1)
				(type default)
			)
			(layer "B.Fab")
		)
		(fp_line
			(start 0.12065 0.2794)
			(end 0.12065 0.3048)
			(stroke
				(width 0.1)
				(type default)
			)
			(layer "B.Fab")
		)
		(fp_line
			(start -0.12065 -0.2794)
			(end -0.12065 -0.3048)
			(stroke
				(width 0.1)
				(type default)
			)
			(layer "B.Fab")
		)
		(fp_line
			(start 0.12065 -0.2794)
			(end -0.12065 -0.2794)
			(stroke
				(width 0.1)
				(type default)
			)
			(layer "B.Fab")
		)
		(fp_line
			(start -0.67945 -0.3048)
			(end -0.67945 0.3048)
			(stroke
				(width 0.1)
				(type default)
			)
			(layer "B.Fab")
		)
		(fp_line
			(start -0.12065 -0.3048)
			(end -0.67945 -0.3048)
			(stroke
				(width 0.1)
				(type default)
			)
			(layer "B.Fab")
		)
		(fp_line
			(start 0.12065 -0.305054)
			(end 0.12065 -0.2794)
			(stroke
				(width 0.1)
				(type default)
			)
			(layer "B.Fab")
		)
		(fp_line
			(start 0.67945 -0.305054)
			(end 0.12065 -0.305054)
			(stroke
				(width 0.1)
				(type default)
			)
			(layer "B.Fab")
		)
		(pad "1" smd circle
			(at 0.40005 0 90)
			(size 0 0)
			(layers "B.Cu" "B.Mask" "B.Paste")
			(net "P3V3_AUX")
		)
		(pad "2" smd circle
			(at -0.40005 0 90)
			(size 0 0)
			(layers "B.Cu" "B.Mask" "B.Paste")
			(net "SMB_USB_CPU0_HUB1_SCL_R2")
		)
	)
	(footprint ""
		(layer "B.Cu")
		(at 163.263326 -408.517344 90)
		(property "Reference" "C6755"
			(at 0 0 90)
			(layer "B.SilkS")
			(hide yes)
			(effects
				(font
					(size 1.27 1.27)
				)
				(justify mirror)
			)
		)
		(property "Value" ""
			(at 0 0 90)
			(layer "B.Fab")
			(effects
				(font
					(size 1.27 1.27)
				)
				(justify mirror)
			)
		)
		(duplicate_pad_numbers_are_jumpers no)
		(fp_line
			(start 0.299974 -0.150114)
			(end -0.299974 -0.150114)
			(stroke
				(width 0.1)
				(type default)
			)
			(layer "B.Fab")
		)
		(fp_line
			(start -0.299974 -0.150114)
			(end -0.299974 0.150114)
			(stroke
				(width 0.1)
				(type default)
			)
			(layer "B.Fab")
		)
		(fp_line
			(start 0.299974 0.150114)
			(end 0.299974 -0.150114)
			(stroke
				(width 0.1)
				(type default)
			)
			(layer "B.Fab")
		)
		(fp_line
			(start -0.299974 0.150114)
			(end 0.299974 0.150114)
			(stroke
				(width 0.1)
				(type default)
			)
			(layer "B.Fab")
		)
		(pad "1" smd rect
			(at 0.2667 0 270)
			(size 0.3048 0.381)
			(layers "B.Cu" "B.Mask" "B.Paste")
			(net "P5E_CPU1_P3_TX_BUF_C_DP<15>")
		)
		(pad "2" smd rect
			(at -0.2667 0 270)
			(size 0.3048 0.381)
			(layers "B.Cu" "B.Mask" "B.Paste")
			(net "P5E_CPU1_P3_TX_BUF_DP<15>")
		)
	)
	(footprint ""
		(layer "B.Cu")
		(at 99.001834 -249.368564 180)
		(property "Reference" "C2670"
			(at 0 0 0)
			(layer "B.SilkS")
			(hide yes)
			(effects
				(font
					(size 1.27 1.27)
				)
				(justify mirror)
			)
		)
		(property "Value" ""
			(at 0 0 0)
			(layer "B.Fab")
			(effects
				(font
					(size 1.27 1.27)
				)
				(justify mirror)
			)
		)
		(duplicate_pad_numbers_are_jumpers no)
		(fp_line
			(start 0.7874 0.4064)
			(end 0.7874 -0.4064)
			(stroke
				(width 0.1524)
				(type default)
			)
			(layer "B.SilkS")
		)
		(fp_line
			(start 0.7874 -0.4064)
			(end -0.7874 -0.4064)
			(stroke
				(width 0.1524)
				(type default)
			)
			(layer "B.SilkS")
		)
		(fp_line
			(start -0.7874 0.4064)
			(end 0.7874 0.4064)
			(stroke
				(width 0.1524)
				(type default)
			)
			(layer "B.SilkS")
		)
		(fp_line
			(start -0.7874 -0.4064)
			(end -0.7874 0.4064)
			(stroke
				(width 0.1524)
				(type default)
			)
			(layer "B.SilkS")
		)
		(fp_line
			(start 0.67945 0.3048)
			(end 0.67945 -0.305054)
			(stroke
				(width 0.1)
				(type default)
			)
			(layer "B.Fab")
		)
		(fp_line
			(start 0.67945 -0.305054)
			(end 0.12065 -0.305054)
			(stroke
				(width 0.1)
				(type default)
			)
			(layer "B.Fab")
		)
		(fp_line
			(start 0.12065 0.3048)
			(end 0.67945 0.3048)
			(stroke
				(width 0.1)
				(type default)
			)
			(layer "B.Fab")
		)
		(fp_line
			(start 0.12065 0.2794)
			(end 0.12065 0.3048)
			(stroke
				(width 0.1)
				(type default)
			)
			(layer "B.Fab")
		)
		(fp_line
			(start 0.12065 -0.2794)
			(end -0.12065 -0.2794)
			(stroke
				(width 0.1)
				(type default)
			)
			(layer "B.Fab")
		)
		(fp_line
			(start 0.12065 -0.305054)
			(end 0.12065 -0.2794)
			(stroke
				(width 0.1)
				(type default)
			)
			(layer "B.Fab")
		)
		(fp_line
			(start -0.120396 0.3048)
			(end -0.120396 0.2794)
			(stroke
				(width 0.1)
				(type default)
			)
			(layer "B.Fab")
		)
		(fp_line
			(start -0.120396 0.2794)
			(end 0.12065 0.2794)
			(stroke
				(width 0.1)
				(type default)
			)
			(layer "B.Fab")
		)
		(fp_line
			(start -0.12065 -0.2794)
			(end -0.12065 -0.3048)
			(stroke
				(width 0.1)
				(type default)
			)
			(layer "B.Fab")
		)
		(fp_line
			(start -0.12065 -0.3048)
			(end -0.67945 -0.3048)
			(stroke
				(width 0.1)
				(type default)
			)
			(layer "B.Fab")
		)
		(fp_line
			(start -0.67945 0.3048)
			(end -0.120396 0.3048)
			(stroke
				(width 0.1)
				(type default)
			)
			(layer "B.Fab")
		)
		(fp_line
			(start -0.67945 -0.3048)
			(end -0.67945 0.3048)
			(stroke
				(width 0.1)
				(type default)
			)
			(layer "B.Fab")
		)
		(pad "1" smd circle
			(at 0.40005 0)
			(size 0 0)
			(layers "B.Cu" "B.Mask" "B.Paste")
			(net "PVDD18_S5_P1")
		)
		(pad "2" smd circle
			(at -0.40005 0)
			(size 0 0)
			(layers "B.Cu" "B.Mask" "B.Paste")
			(net "GND")
		)
	)
	(footprint ""
		(layer "B.Cu")
		(at 428.98695 -36.007548 180)
		(property "Reference" "R1264"
			(at 0 0 0)
			(layer "B.SilkS")
			(hide yes)
			(effects
				(font
					(size 1.27 1.27)
				)
				(justify mirror)
			)
		)
		(property "Value" ""
			(at 0 0 0)
			(layer "B.Fab")
			(effects
				(font
					(size 1.27 1.27)
				)
				(justify mirror)
			)
		)
		(duplicate_pad_numbers_are_jumpers no)
		(fp_line
			(start 0.7874 0.4064)
			(end 0.7874 -0.4064)
			(stroke
				(width 0.1524)
				(type default)
			)
			(layer "B.SilkS")
		)
		(fp_line
			(start 0.7874 -0.4064)
			(end -0.7874 -0.4064)
			(stroke
				(width 0.1524)
				(type default)
			)
			(layer "B.SilkS")
		)
		(fp_line
			(start -0.7874 0.4064)
			(end 0.7874 0.4064)
			(stroke
				(width 0.1524)
				(type default)
			)
			(layer "B.SilkS")
		)
		(fp_line
			(start -0.7874 -0.4064)
			(end -0.7874 0.4064)
			(stroke
				(width 0.1524)
				(type default)
			)
			(layer "B.SilkS")
		)
		(fp_line
			(start 0.67945 0.3048)
			(end 0.67945 -0.305054)
			(stroke
				(width 0.1)
				(type default)
			)
			(layer "B.Fab")
		)
		(fp_line
			(start 0.67945 -0.305054)
			(end 0.12065 -0.305054)
			(stroke
				(width 0.1)
				(type default)
			)
			(layer "B.Fab")
		)
		(fp_line
			(start 0.12065 0.3048)
			(end 0.67945 0.3048)
			(stroke
				(width 0.1)
				(type default)
			)
			(layer "B.Fab")
		)
		(fp_line
			(start 0.12065 0.2794)
			(end 0.12065 0.3048)
			(stroke
				(width 0.1)
				(type default)
			)
			(layer "B.Fab")
		)
		(fp_line
			(start 0.12065 -0.2794)
			(end -0.12065 -0.2794)
			(stroke
				(width 0.1)
				(type default)
			)
			(layer "B.Fab")
		)
		(fp_line
			(start 0.12065 -0.305054)
			(end 0.12065 -0.2794)
			(stroke
				(width 0.1)
				(type default)
			)
			(layer "B.Fab")
		)
		(fp_line
			(start -0.120396 0.3048)
			(end -0.120396 0.2794)
			(stroke
				(width 0.1)
				(type default)
			)
			(layer "B.Fab")
		)
		(fp_line
			(start -0.120396 0.2794)
			(end 0.12065 0.2794)
			(stroke
				(width 0.1)
				(type default)
			)
			(layer "B.Fab")
		)
		(fp_line
			(start -0.12065 -0.2794)
			(end -0.12065 -0.3048)
			(stroke
				(width 0.1)
				(type default)
			)
			(layer "B.Fab")
		)
		(fp_line
			(start -0.12065 -0.3048)
			(end -0.67945 -0.3048)
			(stroke
				(width 0.1)
				(type default)
			)
			(layer "B.Fab")
		)
		(fp_line
			(start -0.67945 0.3048)
			(end -0.120396 0.3048)
			(stroke
				(width 0.1)
				(type default)
			)
			(layer "B.Fab")
		)
		(fp_line
			(start -0.67945 -0.3048)
			(end -0.67945 0.3048)
			(stroke
				(width 0.1)
				(type default)
			)
			(layer "B.Fab")
		)
		(pad "1" smd circle
			(at 0.40005 0)
			(size 0 0)
			(layers "B.Cu" "B.Mask" "B.Paste")
			(net "P1V8_AUX")
		)
		(pad "2" smd circle
			(at -0.40005 0)
			(size 0 0)
			(layers "B.Cu" "B.Mask" "B.Paste")
			(net "BIOS_DEBUG_MODE")
		)
	)
)
